# T6G (Grand Teton) — schematic netlist excerpt (pin names and nets, part order shuffled) for the footprints in the layout excerpt that follows; sources: Cadence DE-HDL packaged netlist, KiCad conversion of 04192023_DAF0TMB3IC0_F0TG_MB_C_brd_V02_OCP.brd

PR6805  Q_RES  1K 1% EMPTY  pkg 0402LF  page 362 : A = P3V3_AUX ; B = P0V9_RETIMER_CPU0_SVID_CLK
C665  Q_CAP  100UF 4V 20% X6S  pkg C0805  page 301 : A = P1V8_CPU0_RT_1D ; B = GND
R3569  Q_RES  0 5% CHIP  pkg 0402LF  page 237 : A = SMB_INA230_3_3V3AUX_SDA_R ; B = SMB_INA230_3_3V3AUX_SDA_R1

(kicad_pcb
	(version 20260206)
	(generator "pcbnew")
	(generator_version "10.0")
	(general
		(thickness 1.6)
		(legacy_teardrops no)
	)
	(paper "A4")
	(title_block
		(title "04192023_DAF0TMB3IC0_F0TG_MB_C_brd_V02_OCP.brd")
		(comment 1 "Grand Teton / footprints 2914-2916 of 8354")
	)
	(layers
		(0 "F.Cu" signal "TOP")
		(4 "In1.Cu" signal "GND")
		(6 "In2.Cu" signal "IN1")
		(8 "In3.Cu" signal "GND1")
		(10 "In4.Cu" signal "IN2")
		(12 "In5.Cu" signal "GND2")
		(14 "In6.Cu" signal "IN3")
		(16 "In7.Cu" signal "GND3")
		(18 "In8.Cu" signal "VCC")
		(20 "In9.Cu" signal "VCC1")
		(22 "In10.Cu" signal "GND4")
		(24 "In11.Cu" signal "IN4")
		(26 "In12.Cu" signal "GND5")
		(28 "In13.Cu" signal "IN5")
		(30 "In14.Cu" signal "GND6")
		(32 "In15.Cu" signal "IN6")
		(34 "In16.Cu" signal "GND7")
		(2 "B.Cu" signal "BOTTOM")
		(9 "F.Adhes" user "F.Adhesive")
		(11 "B.Adhes" user "B.Adhesive")
		(13 "F.Paste" user "Package Geometry/Pastemask Top")
		(15 "B.Paste" user "Package Geometry/Pastemask Bottom")
		(5 "F.SilkS" user "Ref Des/Silkscreen Top")
		(7 "B.SilkS" user "Ref Des/Silkscreen Bottom")
		(1 "F.Mask" user "Board Geometry/Soldermask Top")
		(3 "B.Mask" user "Board Geometry/Soldermask Bottom")
		(17 "Dwgs.User" user "User.Drawings")
		(19 "Cmts.User" user "User.Comments")
		(21 "Eco1.User" user "User.Eco1")
		(23 "Eco2.User" user "User.Eco2")
		(25 "Edge.Cuts" user "Board Geometry/Outline")
		(27 "Margin" user)
		(31 "F.CrtYd" user "Package Geometry/Place Bound Top")
		(29 "B.CrtYd" user "Package Geometry/Place Bound Bottom")
		(35 "F.Fab" user "Ref Des/Assembly Top")
		(33 "B.Fab" user "Ref Des/Assembly Bottom")
	)
	(footprint ""
		(layer "F.Cu")
		(at 70.7136 -34.788348)
		(property "Reference" "R3569"
			(at 0 0 0)
			(layer "F.SilkS")
			(hide yes)
			(effects
				(font
					(size 1.27 1.27)
				)
			)
		)
		(property "Value" ""
			(at 0 0 0)
			(layer "F.Fab")
			(effects
				(font
					(size 1.27 1.27)
				)
			)
		)
		(duplicate_pad_numbers_are_jumpers no)
		(fp_line
			(start -0.7874 -0.4064)
			(end 0.7874 -0.4064)
			(stroke
				(width 0.1524)
				(type default)
			)
			(layer "F.SilkS")
		)
		(fp_line
			(start -0.7874 0.4064)
			(end -0.7874 -0.4064)
			(stroke
				(width 0.1524)
				(type default)
			)
			(layer "F.SilkS")
		)
		(fp_line
			(start 0.7874 -0.4064)
			(end 0.7874 0.4064)
			(stroke
				(width 0.1524)
				(type default)
			)
			(layer "F.SilkS")
		)
		(fp_line
			(start 0.7874 0.4064)
			(end -0.7874 0.4064)
			(stroke
				(width 0.1524)
				(type default)
			)
			(layer "F.SilkS")
		)
		(fp_line
			(start -0.67945 -0.305054)
			(end -0.12065 -0.305054)
			(stroke
				(width 0.1)
				(type default)
			)
			(layer "F.Fab")
		)
		(fp_line
			(start -0.67945 0.3048)
			(end -0.67945 -0.305054)
			(stroke
				(width 0.1)
				(type default)
			)
			(layer "F.Fab")
		)
		(fp_line
			(start -0.12065 -0.305054)
			(end -0.12065 -0.2794)
			(stroke
				(width 0.1)
				(type default)
			)
			(layer "F.Fab")
		)
		(fp_line
			(start -0.12065 -0.2794)
			(end 0.12065 -0.2794)
			(stroke
				(width 0.1)
				(type default)
			)
			(layer "F.Fab")
		)
		(fp_line
			(start -0.12065 0.2794)
			(end -0.12065 0.3048)
			(stroke
				(width 0.1)
				(type default)
			)
			(layer "F.Fab")
		)
		(fp_line
			(start -0.12065 0.3048)
			(end -0.67945 0.3048)
			(stroke
				(width 0.1)
				(type default)
			)
			(layer "F.Fab")
		)
		(fp_line
			(start 0.120396 0.2794)
			(end -0.12065 0.2794)
			(stroke
				(width 0.1)
				(type default)
			)
			(layer "F.Fab")
		)
		(fp_line
			(start 0.120396 0.3048)
			(end 0.120396 0.2794)
			(stroke
				(width 0.1)
				(type default)
			)
			(layer "F.Fab")
		)
		(fp_line
			(start 0.12065 -0.3048)
			(end 0.67945 -0.3048)
			(stroke
				(width 0.1)
				(type default)
			)
			(layer "F.Fab")
		)
		(fp_line
			(start 0.12065 -0.2794)
			(end 0.12065 -0.3048)
			(stroke
				(width 0.1)
				(type default)
			)
			(layer "F.Fab")
		)
		(fp_line
			(start 0.67945 -0.3048)
			(end 0.67945 0.3048)
			(stroke
				(width 0.1)
				(type default)
			)
			(layer "F.Fab")
		)
		(fp_line
			(start 0.67945 0.3048)
			(end 0.120396 0.3048)
			(stroke
				(width 0.1)
				(type default)
			)
			(layer "F.Fab")
		)
		(pad "1" smd circle
			(at -0.40005 0)
			(size 0 0)
			(layers "F.Cu" "F.Mask" "F.Paste")
			(net "SMB_INA230_3_3V3AUX_SDA_R")
		)
		(pad "2" smd circle
			(at 0.40005 0)
			(size 0 0)
			(layers "F.Cu" "F.Mask" "F.Paste")
			(net "SMB_INA230_3_3V3AUX_SDA_R1")
		)
	)
	(footprint ""
		(layer "F.Cu")
		(at 439.029602 -423.66311)
		(property "Reference" "PR6805"
			(at 0 0 0)
			(layer "F.SilkS")
			(hide yes)
			(effects
				(font
					(size 1.27 1.27)
				)
			)
		)
		(property "Value" ""
			(at 0 0 0)
			(layer "F.Fab")
			(effects
				(font
					(size 1.27 1.27)
				)
			)
		)
		(duplicate_pad_numbers_are_jumpers no)
		(fp_line
			(start -0.7874 -0.4064)
			(end 0.7874 -0.4064)
			(stroke
				(width 0.1524)
				(type default)
			)
			(layer "F.SilkS")
		)
		(fp_line
			(start -0.7874 0.4064)
			(end -0.7874 -0.4064)
			(stroke
				(width 0.1524)
				(type default)
			)
			(layer "F.SilkS")
		)
		(fp_line
			(start 0.7874 -0.4064)
			(end 0.7874 0.4064)
			(stroke
				(width 0.1524)
				(type default)
			)
			(layer "F.SilkS")
		)
		(fp_line
			(start 0.7874 0.4064)
			(end -0.7874 0.4064)
			(stroke
				(width 0.1524)
				(type default)
			)
			(layer "F.SilkS")
		)
		(fp_line
			(start -0.67945 -0.305054)
			(end -0.12065 -0.305054)
			(stroke
				(width 0.1)
				(type default)
			)
			(layer "F.Fab")
		)
		(fp_line
			(start -0.67945 0.3048)
			(end -0.67945 -0.305054)
			(stroke
				(width 0.1)
				(type default)
			)
			(layer "F.Fab")
		)
		(fp_line
			(start -0.12065 -0.305054)
			(end -0.12065 -0.2794)
			(stroke
				(width 0.1)
				(type default)
			)
			(layer "F.Fab")
		)
		(fp_line
			(start -0.12065 -0.2794)
			(end 0.12065 -0.2794)
			(stroke
				(width 0.1)
				(type default)
			)
			(layer "F.Fab")
		)
		(fp_line
			(start -0.12065 0.2794)
			(end -0.12065 0.3048)
			(stroke
				(width 0.1)
				(type default)
			)
			(layer "F.Fab")
		)
		(fp_line
			(start -0.12065 0.3048)
			(end -0.67945 0.3048)
			(stroke
				(width 0.1)
				(type default)
			)
			(layer "F.Fab")
		)
		(fp_line
			(start 0.120396 0.2794)
			(end -0.12065 0.2794)
			(stroke
				(width 0.1)
				(type default)
			)
			(layer "F.Fab")
		)
		(fp_line
			(start 0.120396 0.3048)
			(end 0.120396 0.2794)
			(stroke
				(width 0.1)
				(type default)
			)
			(layer "F.Fab")
		)
		(fp_line
			(start 0.12065 -0.3048)
			(end 0.67945 -0.3048)
			(stroke
				(width 0.1)
				(type default)
			)
			(layer "F.Fab")
		)
		(fp_line
			(start 0.12065 -0.2794)
			(end 0.12065 -0.3048)
			(stroke
				(width 0.1)
				(type default)
			)
			(layer "F.Fab")
		)
		(fp_line
			(start 0.67945 -0.3048)
			(end 0.67945 0.3048)
			(stroke
				(width 0.1)
				(type default)
			)
			(layer "F.Fab")
		)
		(fp_line
			(start 0.67945 0.3048)
			(end 0.120396 0.3048)
			(stroke
				(width 0.1)
				(type default)
			)
			(layer "F.Fab")
		)
		(pad "1" smd circle
			(at -0.40005 0)
			(size 0 0)
			(layers "F.Cu" "F.Mask" "F.Paste")
			(net "P3V3_AUX")
		)
		(pad "2" smd circle
			(at 0.40005 0)
			(size 0 0)
			(layers "F.Cu" "F.Mask" "F.Paste")
			(net "P0V9_RETIMER_CPU0_SVID_CLK")
		)
	)
	(footprint ""
		(layer "F.Cu")
		(at 429.278796 -393.9032 90)
		(property "Reference" "C665"
			(at 0 0 90)
			(layer "F.SilkS")
			(hide yes)
			(effects
				(font
					(size 1.27 1.27)
				)
			)
		)
		(property "Value" ""
			(at 0 0 90)
			(layer "F.Fab")
			(effects
				(font
					(size 1.27 1.27)
				)
			)
		)
		(duplicate_pad_numbers_are_jumpers no)
		(fp_line
			(start 1.524 -0.762)
			(end 1.524 0.762)
			(stroke
				(width 0.1524)
				(type default)
			)
			(layer "F.SilkS")
		)
		(fp_line
			(start -1.524 -0.762)
			(end 1.524 -0.762)
			(stroke
				(width 0.1524)
				(type default)
			)
			(layer "F.SilkS")
		)
		(fp_line
			(start 1.524 0.762)
			(end -1.524 0.762)
			(stroke
				(width 0.1524)
				(type default)
			)
			(layer "F.SilkS")
		)
		(fp_line
			(start -1.524 0.762)
			(end -1.524 -0.762)
			(stroke
				(width 0.1524)
				(type default)
			)
			(layer "F.SilkS")
		)
		(fp_line
			(start 1.1049 -0.724916)
			(end -1.1049 -0.724916)
			(stroke
				(width 0.1)
				(type default)
			)
			(layer "F.Fab")
		)
		(fp_line
			(start -1.1049 -0.724916)
			(end -1.1049 0.724916)
			(stroke
				(width 0.1)
				(type default)
			)
			(layer "F.Fab")
		)
		(fp_line
			(start 1.1049 0.724916)
			(end 1.1049 -0.724916)
			(stroke
				(width 0.1)
				(type default)
			)
			(layer "F.Fab")
		)
		(fp_line
			(start -1.1049 0.724916)
			(end 1.1049 0.724916)
			(stroke
				(width 0.1)
				(type default)
			)
			(layer "F.Fab")
		)
		(pad "1" smd rect
			(at -0.889 0 270)
			(size 1.016 1.27)
			(layers "F.Cu" "F.Mask" "F.Paste")
			(net "P1V8_CPU0_RT_1D")
		)
		(pad "2" smd rect
			(at 0.889 0 270)
			(size 1.016 1.27)
			(layers "F.Cu" "F.Mask" "F.Paste")
			(net "GND")
		)
	)
)
